(kicad_pcb
	(version 20241229)
	(generator "pcbnew")
	(generator_version "9.0")
	(general
		(thickness 1.711)
		(legacy_teardrops no)
	)
	(paper "A4")
	(title_block
		(title "Antmicro Baseboard for Jetson AGX Thor")
		(date "2026-02-18")
		(rev "1.1.0")
		(company "Antmicro Ltd")
		(comment 1 "www.antmicro.com")
		(comment 9 "footprints 847-851 of 1170")
	)
	(layers
		(0 "F.Cu" signal)
		(4 "In1.Cu" signal)
		(6 "In2.Cu" signal)
		(8 "In3.Cu" signal)
		(10 "In4.Cu" jumper)
		(12 "In5.Cu" signal)
		(14 "In6.Cu" signal)
		(16 "In7.Cu" signal)
		(18 "In8.Cu" signal)
		(2 "B.Cu" signal)
		(9 "F.Adhes" user "F.Adhesive")
		(11 "B.Adhes" user "B.Adhesive")
		(13 "F.Paste" user)
		(15 "B.Paste" user)
		(5 "F.SilkS" user "F.Silkscreen")
		(7 "B.SilkS" user "B.Silkscreen")
		(1 "F.Mask" user)
		(3 "B.Mask" user)
		(17 "Dwgs.User" user "User.Drawings")
		(19 "Cmts.User" user "User.Comments")
		(21 "Eco1.User" user "User.Eco1")
		(23 "Eco2.User" user "User.Eco2")
		(25 "Edge.Cuts" user)
		(27 "Margin" user)
		(31 "F.CrtYd" user "F.Courtyard")
		(29 "B.CrtYd" user "B.Courtyard")
		(35 "F.Fab" user)
		(33 "B.Fab" user)
	)
	(footprint "antmicro-footprints:R_0402_1005Metric"
		(layer "B.Cu")
		(at 217.452132 95.392)
		(descr "Resistor SMD 0402")
		(tags "resistor SMD 0402")
		(property "Reference" "R274"
			(at -1.052132 -1.492 0)
			(layer "B.SilkS")
			(effects
				(font
					(size 0.7 0.7)
					(thickness 0.15)
				)
				(justify right top mirror)
			)
		)
		(property "Value" "R_10k_0402"
			(at -1.011843 -1.772047 0)
			(layer "B.Fab")
			(effects
				(font
					(size 0.7 0.7)
					(thickness 0.15)
				)
				(justify right top mirror)
			)
		)
		(property "Datasheet" "https://www.bourns.com/docs/product-datasheets/cr.pdf"
			(at 0 0 0)
			(layer "B.Fab")
			(hide yes)
			(effects
				(font
					(size 1.27 1.27)
					(thickness 0.15)
				)
				(justify mirror)
			)
		)
		(property "Description" "SMD Chip Resistor, 10 kohm, ± 1%, 62.5 mW, 0402 [1005 Metric], Thick Film, General Purpose"
			(at 0 0 0)
			(layer "B.Fab")
			(hide yes)
			(effects
				(font
					(size 1.27 1.27)
					(thickness 0.15)
				)
				(justify mirror)
			)
		)
		(property "MPN" "CR0402-FX-1002GLF"
			(at 0 0 180)
			(unlocked yes)
			(layer "B.Fab")
			(hide yes)
			(effects
				(font
					(size 1 1)
					(thickness 0.15)
				)
				(justify mirror)
			)
		)
		(property "Manufacturer" "Bourns"
			(at 0 0 180)
			(unlocked yes)
			(layer "B.Fab")
			(hide yes)
			(effects
				(font
					(size 1 1)
					(thickness 0.15)
				)
				(justify mirror)
			)
		)
		(property "License" "Apache-2.0"
			(at 0 0 180)
			(unlocked yes)
			(layer "B.Fab")
			(hide yes)
			(effects
				(font
					(size 1 1)
					(thickness 0.15)
				)
				(justify mirror)
			)
		)
		(property "Author" "Antmicro"
			(at 0 0 180)
			(unlocked yes)
			(layer "B.Fab")
			(hide yes)
			(effects
				(font
					(size 1 1)
					(thickness 0.15)
				)
				(justify mirror)
			)
		)
		(property "Val" "10k"
			(at 0 0 180)
			(unlocked yes)
			(layer "B.Fab")
			(hide yes)
			(effects
				(font
					(size 1 1)
					(thickness 0.15)
				)
				(justify mirror)
			)
		)
		(property "Tolerance" "1%"
			(at 0 0 180)
			(unlocked yes)
			(layer "B.Fab")
			(hide yes)
			(effects
				(font
					(size 1 1)
					(thickness 0.15)
				)
				(justify mirror)
			)
		)
		(sheetname "/USB DP Alt mode/")
		(sheetfile "usb_dp.kicad_sch")
		(attr smd)
		(fp_rect
			(start -0.925 0.47)
			(end 0.925 -0.47)
			(stroke
				(width 0.05)
				(type default)
			)
			(fill no)
			(layer "B.CrtYd")
		)
		(fp_rect
			(start -0.5 0.25)
			(end 0.5 -0.25)
			(stroke
				(width 0.15)
				(type solid)
			)
			(fill no)
			(layer "B.Fab")
		)
		(fp_text user "${REFERENCE}"
			(at -0.95 -3.168 0)
			(layer "B.Fab")
			(effects
				(font
					(size 0.7 0.7)
					(thickness 0.15)
				)
				(justify right top mirror)
			)
		)
		(fp_text user "License: Apache-2.0"
			(at -0.95 -5.169 0)
			(layer "B.Fab")
			(effects
				(font
					(size 0.7 0.7)
					(thickness 0.15)
				)
				(justify right top mirror)
			)
		)
		(fp_text user "Author: Antmicro"
			(at -0.95 -4.169 0)
			(layer "B.Fab")
			(effects
				(font
					(size 0.7 0.7)
					(thickness 0.15)
				)
				(justify right top mirror)
			)
		)
		(pad "1" smd roundrect
			(at -0.48 0)
			(size 0.59 0.64)
			(layers "B.Cu" "B.Mask" "B.Paste")
			(roundrect_rratio 0.25)
			(net 1301 "Net-(Q35-D)")
			(pintype "passive")
		)
		(pad "2" smd roundrect
			(at 0.48 0)
			(size 0.59 0.64)
			(layers "B.Cu" "B.Mask" "B.Paste")
			(roundrect_rratio 0.25)
			(net 11 "+1V8")
			(pintype "passive")
		)
	)
	(footprint "antmicro-footprints:R_0603_1608Metric"
		(layer "B.Cu")
		(at 100.1 129.2 180)
		(descr "Resistor SMD 0603")
		(tags "resistor SMD 0603")
		(property "Reference" "R249"
			(at -4.23 -0.33 0)
			(layer "B.SilkS")
			(effects
				(font
					(size 0.7 0.7)
					(thickness 0.15)
				)
				(justify left bottom mirror)
			)
		)
		(property "Value" "R_0R_22.4A_0603"
			(at 0 -1.6 0)
			(layer "B.Fab")
			(effects
				(font
					(size 0.7 0.7)
					(thickness 0.15)
				)
				(justify left bottom mirror)
			)
		)
		(property "Datasheet" "https://fscdn.rohm.com/en/products/databook/datasheet/passive/resistor/chip_resistor/pmr-jpw-e.pdf"
			(at 0 0 0)
			(layer "B.Fab")
			(hide yes)
			(effects
				(font
					(size 1.27 1.27)
					(thickness 0.15)
				)
				(justify mirror)
			)
		)
		(property "Description" "SMD Chip Resistor"
			(at 0 0 0)
			(layer "B.Fab")
			(hide yes)
			(effects
				(font
					(size 1.27 1.27)
					(thickness 0.15)
				)
				(justify mirror)
			)
		)
		(property "MPN" "PMR03EZPJ000"
			(at 0 0 0)
			(unlocked yes)
			(layer "B.Fab")
			(hide yes)
			(effects
				(font
					(size 1 1)
					(thickness 0.15)
				)
				(justify mirror)
			)
		)
		(property "Manufacturer" "ROHM Semiconductor"
			(at 0 0 0)
			(unlocked yes)
			(layer "B.Fab")
			(hide yes)
			(effects
				(font
					(size 1 1)
					(thickness 0.15)
				)
				(justify mirror)
			)
		)
		(property "Val" "0R"
			(at 0 0 0)
			(unlocked yes)
			(layer "B.Fab")
			(hide yes)
			(effects
				(font
					(size 1 1)
					(thickness 0.15)
				)
				(justify mirror)
			)
		)
		(property "Max. Curr." "22.4A"
			(at 0 0 0)
			(unlocked yes)
			(layer "B.Fab")
			(hide yes)
			(effects
				(font
					(size 1 1)
					(thickness 0.15)
				)
				(justify mirror)
			)
		)
		(property "Author" "Antmicro"
			(at 0 0 0)
			(unlocked yes)
			(layer "B.Fab")
			(hide yes)
			(effects
				(font
					(size 1 1)
					(thickness 0.15)
				)
				(justify mirror)
			)
		)
		(property "License" "Apache-2.0"
			(at 0 0 0)
			(unlocked yes)
			(layer "B.Fab")
			(hide yes)
			(effects
				(font
					(size 1 1)
					(thickness 0.15)
				)
				(justify mirror)
			)
		)
		(property "Tolerance" "template_tolerance"
			(at 0 0 0)
			(unlocked yes)
			(layer "B.Fab")
			(hide yes)
			(effects
				(font
					(size 1 1)
					(thickness 0.15)
				)
				(justify mirror)
			)
		)
		(sheetname "/Expansion connector/")
		(sheetfile "expansion_connector.kicad_sch")
		(attr smd exclude_from_pos_files exclude_from_bom dnp)
		(fp_line
			(start -0.15 0.4)
			(end 0.15 0.4)
			(stroke
				(width 0.15)
				(type solid)
			)
			(layer "B.SilkS")
		)
		(fp_line
			(start -0.15 -0.4)
			(end 0.15 -0.4)
			(stroke
				(width 0.15)
				(type solid)
			)
			(layer "B.SilkS")
		)
		(fp_rect
			(start -1.25 0.65)
			(end 1.25 -0.65)
			(stroke
				(width 0.05)
				(type solid)
			)
			(fill no)
			(layer "B.CrtYd")
		)
		(fp_rect
			(start -0.8 0.4)
			(end 0.8 -0.4)
			(stroke
				(width 0.15)
				(type solid)
			)
			(fill no)
			(layer "B.Fab")
		)
		(fp_text user "${REFERENCE}"
			(at -1.25 -3.898 0)
			(layer "B.Fab")
			(effects
				(font
					(size 0.7 0.7)
					(thickness 0.15)
				)
				(justify left bottom mirror)
			)
		)
		(fp_text user "License: Apache-2.0"
			(at -1.25 -5.9 0)
			(layer "B.Fab")
			(effects
				(font
					(size 0.7 0.7)
					(thickness 0.15)
				)
				(justify left bottom mirror)
			)
		)
		(fp_text user "Author: Antmicro"
			(at -1.25 -4.9 0)
			(layer "B.Fab")
			(effects
				(font
					(size 0.7 0.7)
					(thickness 0.15)
				)
				(justify left bottom mirror)
			)
		)
		(pad "1" smd roundrect
			(at -0.7 0 180)
			(size 0.8 1)
			(layers "B.Cu" "B.Mask" "B.Paste")
			(roundrect_rratio 0.2)
			(net 2 "+3V3")
			(pintype "passive")
		)
		(pad "2" smd roundrect
			(at 0.7 0 180)
			(size 0.8 1)
			(layers "B.Cu" "B.Mask" "B.Paste")
			(roundrect_rratio 0.2)
			(net 297 "/Expansion connector/+3V3_FMC")
			(pintype "passive")
		)
	)
	(footprint "antmicro-footprints:R_0402_1005Metric"
		(layer "B.Cu")
		(at 124.6 130.8)
		(descr "Resistor SMD 0402")
		(tags "resistor SMD 0402")
		(property "Reference" "R223"
			(at -1.19 -5.32 0)
			(layer "B.SilkS")
			(effects
				(font
					(size 0.7 0.7)
					(thickness 0.15)
				)
				(justify right top mirror)
			)
		)
		(property "Value" "R_0R_0402"
			(at -1.011843 -1.772046 0)
			(layer "B.Fab")
			(effects
				(font
					(size 0.7 0.7)
					(thickness 0.15)
				)
				(justify right top mirror)
			)
		)
		(property "Datasheet" "https://industrial.panasonic.com/cdbs/www-data/pdf/RDA0000/AOA0000C301.pdf"
			(at 0 0 0)
			(layer "B.Fab")
			(hide yes)
			(effects
				(font
					(size 1.27 1.27)
					(thickness 0.15)
				)
				(justify mirror)
			)
		)
		(property "Description" "SMD Chip Resistor, Jumper, 0 ohm, 100 mW, 0402 [1005 Metric], Thick Film, General Purpose"
			(at 0 0 0)
			(layer "B.Fab")
			(hide yes)
			(effects
				(font
					(size 1.27 1.27)
					(thickness 0.15)
				)
				(justify mirror)
			)
		)
		(property "MPN" "ERJ2GE0R00X"
			(at 0 0 180)
			(unlocked yes)
			(layer "B.Fab")
			(hide yes)
			(effects
				(font
					(size 1 1)
					(thickness 0.15)
				)
				(justify mirror)
			)
		)
		(property "Manufacturer" "Panasonic"
			(at 0 0 180)
			(unlocked yes)
			(layer "B.Fab")
			(hide yes)
			(effects
				(font
					(size 1 1)
					(thickness 0.15)
				)
				(justify mirror)
			)
		)
		(property "License" "Apache-2.0"
			(at 0 0 180)
			(unlocked yes)
			(layer "B.Fab")
			(hide yes)
			(effects
				(font
					(size 1 1)
					(thickness 0.15)
				)
				(justify mirror)
			)
		)
		(property "Val" "0R"
			(at 0 0 180)
			(unlocked yes)
			(layer "B.Fab")
			(hide yes)
			(effects
				(font
					(size 1 1)
					(thickness 0.15)
				)
				(justify mirror)
			)
		)
		(property "Tolerance" "~"
			(at 0 0 180)
			(unlocked yes)
			(layer "B.Fab")
			(hide yes)
			(effects
				(font
					(size 1 1)
					(thickness 0.15)
				)
				(justify mirror)
			)
		)
		(property "Current" "1A"
			(at 0 0 180)
			(unlocked yes)
			(layer "B.Fab")
			(hide yes)
			(effects
				(font
					(size 1 1)
					(thickness 0.15)
				)
				(justify mirror)
			)
		)
		(property "Author" "Antmicro"
			(at 0 0 180)
			(unlocked yes)
			(layer "B.Fab")
			(hide yes)
			(effects
				(font
					(size 1 1)
					(thickness 0.15)
				)
				(justify mirror)
			)
		)
		(property "Public" "False"
			(at 0 0 180)
			(unlocked yes)
			(layer "B.Fab")
			(hide yes)
			(effects
				(font
					(size 1 1)
					(thickness 0.15)
				)
				(justify mirror)
			)
		)
		(sheetname "/M.2/")
		(sheetfile "m2.kicad_sch")
		(attr smd)
		(fp_poly
			(pts
				(xy -0.925 0.47) (xy 0.925 0.47) (xy 0.925 -0.47) (xy -0.925 -0.47)
			)
			(stroke
				(width 0.05)
				(type default)
			)
			(fill no)
			(layer "B.CrtYd")
		)
		(fp_poly
			(pts
				(xy -0.5 0.25) (xy 0.5 0.25) (xy 0.5 -0.25) (xy -0.5 -0.25)
			)
			(stroke
				(width 0.15)
				(type solid)
			)
			(fill no)
			(layer "B.Fab")
		)
		(fp_text user "Author: Antmicro"
			(at -0.95 -4.169 0)
			(layer "B.Fab")
			(effects
				(font
					(size 0.7 0.7)
					(thickness 0.15)
				)
				(justify right top mirror)
			)
		)
		(fp_text user "${REFERENCE}"
			(at -0.95 -3.168 0)
			(layer "B.Fab")
			(effects
				(font
					(size 0.7 0.7)
					(thickness 0.15)
				)
				(justify right top mirror)
			)
		)
		(fp_text user "License: Apache-2.0"
			(at -0.949999 -5.169 0)
			(layer "B.Fab")
			(effects
				(font
					(size 0.7 0.7)
					(thickness 0.15)
				)
				(justify right top mirror)
			)
		)
		(pad "1" smd roundrect
			(at -0.48 0)
			(size 0.59 0.64)
			(layers "B.Cu" "B.Mask" "B.Paste")
			(roundrect_rratio 0.25)
			(net 832 "/M.2/M2_E_SUSCLK")
			(pintype "passive")
		)
		(pad "2" smd roundrect
			(at 0.48 0)
			(size 0.59 0.64)
			(layers "B.Cu" "B.Mask" "B.Paste")
			(roundrect_rratio 0.25)
			(net 1005 "/M.2/SUSCLK")
			(pintype "passive")
		)
	)
	(footprint "antmicro-footprints:SOD-523"
		(layer "B.Cu")
		(at 208.9 83.9 90)
		(property "Reference" "D17"
			(at -1.2 -1.5 90)
			(layer "B.SilkS")
			(effects
				(font
					(size 0.7 0.7)
					(thickness 0.15)
				)
				(justify right top mirror)
			)
		)
		(property "Value" "RB521S30T1G"
			(at 0 -1.499 90)
			(layer "B.Fab")
			(effects
				(font
					(size 0.7 0.7)
					(thickness 0.15)
				)
				(justify right top mirror)
			)
		)
		(property "Datasheet" "https://www.onsemi.com/pdf/datasheet/rb521s30t1-d.pdf"
			(at 0 0 90)
			(layer "B.Fab")
			(hide yes)
			(effects
				(font
					(size 1.27 1.27)
					(thickness 0.15)
				)
				(justify mirror)
			)
		)
		(property "Description" "Small Signal Schottky Diode, Single, 30 V, 200 mA, 500 mV, 1 A, 125 °C"
			(at 0 0 90)
			(layer "B.Fab")
			(hide yes)
			(effects
				(font
					(size 1.27 1.27)
					(thickness 0.15)
				)
				(justify mirror)
			)
		)
		(property "MPN" "RB521S30T1G"
			(at 0 0 270)
			(unlocked yes)
			(layer "B.Fab")
			(hide yes)
			(effects
				(font
					(size 1 1)
					(thickness 0.15)
				)
				(justify mirror)
			)
		)
		(property "Manufacturer" "ON Semiconductor"
			(at 0 0 270)
			(unlocked yes)
			(layer "B.Fab")
			(hide yes)
			(effects
				(font
					(size 1 1)
					(thickness 0.15)
				)
				(justify mirror)
			)
		)
		(property "Author" "Antmicro"
			(at 0 0 270)
			(unlocked yes)
			(layer "B.Fab")
			(hide yes)
			(effects
				(font
					(size 1 1)
					(thickness 0.15)
				)
				(justify mirror)
			)
		)
		(property "License" "Apache-2.0"
			(at 0 0 270)
			(unlocked yes)
			(layer "B.Fab")
			(hide yes)
			(effects
				(font
					(size 1 1)
					(thickness 0.15)
				)
				(justify mirror)
			)
		)
		(sheetname "/USB Debug, PD/")
		(sheetfile "usb_debug_pd.kicad_sch")
		(attr smd)
		(fp_line
			(start -0.35 0.5)
			(end -0.35 -0.5)
			(stroke
				(width 0.15)
				(type solid)
			)
			(layer "B.SilkS")
		)
		(fp_poly
			(pts
				(xy -1 0.6) (xy -1 -0.6) (xy 1 -0.6) (xy 1 0.6)
			)
			(stroke
				(width 0.05)
				(type solid)
			)
			(fill no)
			(layer "B.CrtYd")
		)
		(fp_line
			(start -0.652 -0.423)
			(end 0.65 -0.423)
			(stroke
				(width 0.15)
				(type solid)
			)
			(layer "B.Fab")
		)
		(fp_line
			(start -0.652 -0.423)
			(end -0.652 0.425)
			(stroke
				(width 0.15)
				(type solid)
			)
			(layer "B.Fab")
		)
		(fp_line
			(start -0.35 0.4)
			(end -0.35 -0.4)
			(stroke
				(width 0.15)
				(type solid)
			)
			(layer "B.Fab")
		)
		(fp_line
			(start 0.65 0.425)
			(end 0.65 -0.423)
			(stroke
				(width 0.15)
				(type solid)
			)
			(layer "B.Fab")
		)
		(fp_line
			(start -0.652 0.425)
			(end 0.65 0.425)
			(stroke
				(width 0.15)
				(type solid)
			)
			(layer "B.Fab")
		)
		(fp_text user "License: Apache-2.0"
			(at -1.276 -5.9 90)
			(layer "B.Fab")
			(effects
				(font
					(size 0.7 0.7)
					(thickness 0.15)
				)
				(justify right top mirror)
			)
		)
		(fp_text user "Author: Antmicro"
			(at -1.276 -4.7 90)
			(layer "B.Fab")
			(effects
				(font
					(size 0.7 0.7)
					(thickness 0.15)
				)
				(justify right top mirror)
			)
		)
		(fp_text user "${REFERENCE}"
			(at -1.276 -3.499 90)
			(layer "B.Fab")
			(effects
				(font
					(size 0.7 0.7)
					(thickness 0.15)
				)
				(justify right top mirror)
			)
		)
		(pad "1" smd roundrect
			(at -0.701 0 90)
			(size 0.5 0.6)
			(layers "B.Cu" "B.Mask" "B.Paste")
			(roundrect_rratio 0.25)
			(net 271 "FLASH_PWR")
			(pinfunction "C")
			(pintype "passive")
		)
		(pad "2" smd roundrect
			(at 0.699001 0 90)
			(size 0.5 0.6)
			(layers "B.Cu" "B.Mask" "B.Paste")
			(roundrect_rratio 0.25)
			(net 294 "/USB Debug, PD/PDC_LDO_3V3")
			(pinfunction "A")
			(pintype "passive")
		)
	)
	(footprint "antmicro-footprints:R_0402_1005Metric"
		(layer "B.Cu")
		(at 217.55 114.03)
		(descr "Resistor SMD 0402")
		(tags "resistor SMD 0402")
		(property "Reference" "R331"
			(at -1.76 1.79 0)
			(layer "B.SilkS")
			(effects
				(font
					(size 0.7 0.7)
					(thickness 0.15)
				)
				(justify right top mirror)
			)
		)
		(property "Value" "R_2R2_0402"
			(at -1.011843 -1.772047 0)
			(layer "B.Fab")
			(effects
				(font
					(size 0.7 0.7)
					(thickness 0.15)
				)
				(justify right top mirror)
			)
		)
		(property "Datasheet" "https://www.bourns.com/docs/product-datasheets/cr.pdf"
			(at 0 0 0)
			(layer "B.Fab")
			(hide yes)
			(effects
				(font
					(size 1.27 1.27)
					(thickness 0.15)
				)
				(justify mirror)
			)
		)
		(property "Description" "SMD Chip Resistor, 2.2 ohm, ± 1%, 62.5 mW, 0402 [1005 Metric], Thick Film, General Purpose"
			(at 0 0 0)
			(layer "B.Fab")
			(hide yes)
			(effects
				(font
					(size 1.27 1.27)
					(thickness 0.15)
				)
				(justify mirror)
			)
		)
		(property "MPN" "CR0402-FX-2R20GLF"
			(at 0 0 180)
			(unlocked yes)
			(layer "B.Fab")
			(hide yes)
			(effects
				(font
					(size 1 1)
					(thickness 0.15)
				)
				(justify mirror)
			)
		)
		(property "Manufacturer" "Bourns"
			(at 0 0 180)
			(unlocked yes)
			(layer "B.Fab")
			(hide yes)
			(effects
				(font
					(size 1 1)
					(thickness 0.15)
				)
				(justify mirror)
			)
		)
		(property "License" "Apache-2.0"
			(at 0 0 180)
			(unlocked yes)
			(layer "B.Fab")
			(hide yes)
			(effects
				(font
					(size 1 1)
					(thickness 0.15)
				)
				(justify mirror)
			)
		)
		(property "Author" "Antmicro"
			(at 0 0 180)
			(unlocked yes)
			(layer "B.Fab")
			(hide yes)
			(effects
				(font
					(size 1 1)
					(thickness 0.15)
				)
				(justify mirror)
			)
		)
		(property "Val" "2R2"
			(at 0 0 180)
			(unlocked yes)
			(layer "B.Fab")
			(hide yes)
			(effects
				(font
					(size 1 1)
					(thickness 0.15)
				)
				(justify mirror)
			)
		)
		(property "Tolerance" "1%"
			(at 0 0 180)
			(unlocked yes)
			(layer "B.Fab")
			(hide yes)
			(effects
				(font
					(size 1 1)
					(thickness 0.15)
				)
				(justify mirror)
			)
		)
		(sheetname "/USB Hub/")
		(sheetfile "usb_hub.kicad_sch")
		(attr smd)
		(fp_rect
			(start -0.925 0.47)
			(end 0.925 -0.47)
			(stroke
				(width 0.05)
				(type default)
			)
			(fill no)
			(layer "B.CrtYd")
		)
		(fp_rect
			(start -0.5 0.25)
			(end 0.5 -0.25)
			(stroke
				(width 0.15)
				(type solid)
			)
			(fill no)
			(layer "B.Fab")
		)
		(fp_text user "License: Apache-2.0"
			(at -0.95 -5.169 0)
			(layer "B.Fab")
			(effects
				(font
					(size 0.7 0.7)
					(thickness 0.15)
				)
				(justify right top mirror)
			)
		)
		(fp_text user "Author: Antmicro"
			(at -0.95 -4.169 0)
			(layer "B.Fab")
			(effects
				(font
					(size 0.7 0.7)
					(thickness 0.15)
				)
				(justify right top mirror)
			)
		)
		(fp_text user "${REFERENCE}"
			(at -0.95 -3.168 0)
			(layer "B.Fab")
			(effects
				(font
					(size 0.7 0.7)
					(thickness 0.15)
				)
				(justify right top mirror)
			)
		)
		(pad "1" smd roundrect
			(at -0.48 0)
			(size 0.59 0.64)
			(layers "B.Cu" "B.Mask" "B.Paste")
			(roundrect_rratio 0.25)
			(net 1237 "Net-(D58-C)")
			(pintype "passive")
		)
		(pad "2" smd roundrect
			(at 0.48 0)
			(size 0.59 0.64)
			(layers "B.Cu" "B.Mask" "B.Paste")
			(roundrect_rratio 0.25)
			(net 509 "/USB Hub/USBC3_CC_{2}")
			(pintype "passive")
		)
	)
)
